FILE_TYPE = CONNECTIVITY;
{Allegro Design Entry HDL 17.4-2019 S026 (4007227) 1/17/2022}
"PAGE_NUMBER" = 466;
0"NC";
1"GND\g";
2"P3V3_AUX\g";
3"GND\g";
4"P3V3_AUX\g";
5"GND\g";
6"GND\g";
7"GND\g";
8"P3V3_AUX\g";
9"GND\g";
10"P3V3_AUX\g";
11"P3V3_AUX\g";
12"P3V3_AUX\g";
13"P12V_OCP_SFF_R\g";
14"P12V_OCP_SFF\g";
15"P12V_OCP_SFF\g";
16"P12V_OCP_SFF_ADC_ALERT_R";
17"NC_INA230_7_NC5";
18"E1S_0_P3V3_P12V_ADC_R_ALERT";
19"P12V_E1S_0_R\g";
20"P12V_E1S_0\g";
21"GND\g";
22"P12V_E1S_0\g";
23"GND\g";
24"GND\g";
25"P3V3_AUX\g";
26"P12V_OCP_V3_2_R\g";
27"P12V_OCP_V3_2\g";
28"GND\g";
29"P12V_OCP_V3_2\g";
30"P3V3_AUX\g";
31"GND\g";
32"GND\g";
33"P3V3_AUX\g";
34"NC_INA230_7_NC3";
35"NC_INA230_7_NC1";
36"NC_INA230_6_NC1";
37"NC_INA230_6_NC0";
38"INA230_6_A0";
39"INA230_8_A0";
40"INA230_8_A1";
41"SMB_INA230_7_3V3AUX_SDA_R1";
42"SMB_INA230_7_3V3AUX_SCL_R1";
43"INA230_7_A0";
44"INA230_7_A1";
45"VSENSE_P12V_INA230_6_INP";
46"INA230_6_A1";
47"SMB_INA230_8_3V3AUX_SDA_R";
48"SMB_INA230_8_3V3AUX_SCL_R1";
49"SMB_INA230_8_3V3AUX_SDA_R1";
50"SMB_INA230_6_3V3AUX_SCL_R1";
51"SMB_INA230_6_3V3AUX_SDA_R1";
52"SMB_INA230_7_3V3AUX_SDA_R";
53"SMB_INA230_6_3V3AUX_SDA_R";
54"SMB_INA230_6_3V3AUX_SCL_R";
55"VSENSE_P12V_INA230_7_INN";
56"VSENSE_P12V_INA230_6_INN";
57"P12V_E1S_0_ADC_ALERT_R";
58"OCP_V3_2_P3V3_P12V_ADC_R_ALERT";
59"P12V_OCP_V3_2_ADC_ALERT_R";
60"OCP_SFF_P3V3_P12V_ADC_R_ALERT";
61"NC_INA230_8_NC3";
62"NC_INA230_8_NC2";
63"NC_INA230_8_NC4";
64"NC_INA230_8_NC0";
65"NC_INA230_7_NC2";
66"NC_INA230_8_NC1";
67"NC_INA230_6_NC3";
68"NC_INA230_6_NC2";
69"NC_INA230_6_NC4";
70"NC_INA230_6_NC5";
71"NC_INA230_8_NC5";
72"VSENSE_P12V_INA230_8_INN";
73"VSENSE_P12V_INA230_8_INP";
74"SMB_INA230_8_3V3AUX_SCL_R";
75"NC_INA230_7_NC0";
76"NC_INA230_7_NC4";
77"VSENSE_P12V_INA230_7_INP";
78"SMB_INA230_7_3V3AUX_SCL_R";
%"UNIVERSAL_POWER"
"1","(-8300,5225)","0","pure_quanta_power","I1";
;
HDL_POWER"P12V_OCP_SFF_R"
CDS_LIB"pure_quanta_power";
"A"13;
%"Q_RES"
"1","(-5825,4875)","0","pure_quanta","I10";
;
LOCATION"R1284"
$SEC"1"
CDS_SEC"1"
PACK_TYPE"0402LF"
WATTAGE"1/16W"
TOLERANCE"1%"
VALUE"10"
MATERIAL"CHIP"
CDS_LIB"pure_quanta"
PART_NUMBER"CS01002FB07";
"B"
$PN"2"45;
"A"
$PN"1"15;
%"Q_RES"
"1","(-5825,4600)","0","pure_quanta","I11";
;
LOCATION"R1301"
$SEC"1"
CDS_SEC"1"
TOLERANCE"1%"
PACK_TYPE"0402LF"
MATERIAL"CHIP"
VALUE"10"
WATTAGE"1/16W"
CDS_LIB"pure_quanta"
PART_NUMBER"CS01002FB07";
"B"
$PN"2"56;
"A"
$PN"1"13;
%"Q_RES"
"1","(-6650,5775)","0","pure_quanta","I12";
;
LOCATION"R1306"
$SEC"1"
CDS_SEC"1"
PACK_TYPE"0402LF"
TOLERANCE"1%"
WATTAGE"1/16W"
MATERIAL"EMPTY"
VALUE"4.7K"
CDS_LIB"pure_quanta"
PART_NUMBER"CS24702FB06";
"B"
$PN"2"46;
"A"
$PN"1"21;
%"Q_RES"
"1","(-6650,5725)","0","pure_quanta","I13";
;
LOCATION"R1309"
$SEC"1"
CDS_SEC"1"
WATTAGE"1/16W"
VALUE"4.7K"
PACK_TYPE"0402LF"
MATERIAL"EMPTY"
TOLERANCE"1%"
CDS_LIB"pure_quanta"
PART_NUMBER"CS24702FB06";
"B"
$PN"2"38;
"A"
$PN"1"21;
%"Q_RES"
"1","(-5850,5425)","0","pure_quanta","I14";
;
LOCATION"R1276"
$SEC"1"
CDS_SEC"1"
MATERIAL"CHIP"
VALUE"0"
TOLERANCE"5%"
PACK_TYPE"0402LF"
WATTAGE"1/16W"
CDS_LIB"pure_quanta"
PART_NUMBER"CS00002JB13";
"B"
$PN"2"51;
"A"
$PN"1"53;
%"Q_CAP"
"1","(-5475,4725)","0","pure_quanta","I15";
;
LOCATION"C1111"
$SEC"1"
CDS_SEC"1"
VOLTAGE"25V"
TOLERANCE"10%"
MATERIAL"X7R"
PACK_TYPE"0402"
VALUE"0.1UF"
CDS_LIB"pure_quanta"
PART_NUMBER"CH4104K1B00";
"B"
$PN"2"56;
"A"
$PN"1"45;
%"Q_RES"
"2","(-5550,6075)","0","pure_quanta","I17";
;
LOCATION"R1320"
$SEC"1"
CDS_SEC"1"
MATERIAL"CHIP"
WATTAGE"1/16W"
TOLERANCE"1%"
PACK_TYPE"0402LF"
VALUE"4.7K"
CDS_LIB"pure_quanta"
PART_NUMBER"CS24702FB06";
"A"
$PN"1"2;
"B"
$PN"2"46;
%"UNIVERSAL_GND"
"1","(-4950,5850)","0","pure_quanta_power","I18";
;
CDS_LIB"pure_quanta_power"
HDL_POWER"GND";
"A"1;
%"Q_CAP"
"1","(-4950,6075)","0","pure_quanta","I19";
;
LOCATION"C1097"
$SEC"1"
CDS_SEC"1"
MATERIAL"X7R"
PACK_TYPE"0402"
VOLTAGE"25V"
VALUE"0.1UF"
TOLERANCE"10%"
CDS_LIB"pure_quanta"
PART_NUMBER"CH4104K1B00";
"B"
$PN"2"1;
"A"
$PN"1"33;
%"Q_RES"
"1","(-7725,5075)","0","pure_quanta","I2";
;
LOCATION"R1324"
$SEC"1"
CDS_SEC"1"
TOLERANCE"1%"
WATTAGE"2W"
MATERIAL"CHIP"
PACK_TYPE"2512LF"
VALUE"0.002"
CDS_LIB"pure_quanta"
PART_NUMBER"CS+002AFR06";
"B"
$PN"2"15;
"A"
$PN"1"13;
%"UNIVERSAL_POWER"
"1","(-5550,6375)","0","pure_quanta_power","I20";
;
HDL_POWER"P3V3_AUX"
CDS_LIB"pure_quanta_power";
"A"2;
%"UNIVERSAL_POWER"
"1","(-4700,6475)","0","pure_quanta_power","I21";
;
HDL_POWER"P3V3_AUX"
CDS_LIB"pure_quanta_power";
"A"33;
%"UNIVERSAL_GND"
"1","(-3625,4825)","0","pure_quanta_power","I22";
;
CDS_LIB"pure_quanta_power"
HDL_POWER"GND";
"A"32;
%"Q_RES"
"1","(-2525,5725)","0","pure_quanta","I23";
;
LOCATION"R1270"
$SEC"1"
CDS_SEC"1"
VALUE"0"
MATERIAL"CHIP"
PACK_TYPE"0402LF"
WATTAGE"1/16W"
TOLERANCE"5%"
CDS_LIB"pure_quanta"
PART_NUMBER"CS00002JB13";
"B"
$PN"2"60;
"A"
$PN"1"16;
%"Q_RES"
"1","(-5850,5475)","0","pure_quanta","I27";
;
LOCATION"R1273"
$SEC"1"
CDS_SEC"1"
WATTAGE"1/16W"
VALUE"0"
MATERIAL"CHIP"
TOLERANCE"5%"
PACK_TYPE"0402LF"
CDS_LIB"pure_quanta"
PART_NUMBER"CS00002JB13";
"B"
$PN"2"50;
"A"
$PN"1"54;
%"ISL28022FRZT"
"1","(-4200,5475)","0","pure_quanta","I28";
;
LOCATION"U55"
SEC"1"
PART_TYPE"SMLF"
VALUE"ISL28022FRZ-T"
MATERIAL"IC"
SEC_TYPE""
CDS_LMAN_SYM_OUTLINE"-300,300,300,-300"
NEEDS_NO_SIZE"TRUE"
CDS_LIB"pure_quanta"
PART_NUMBER"AL028022003";
"TH_GND"
$PN"TH"32;
"GND"
$PN"10"32;
"NC5"
$PN"16"70;
"NC4"
$PN"15"69;
"NC3"
$PN"14"67;
"NC2"
$PN"8"68;
"NC1"
$PN"7"36;
"NC0"
$PN"6"37;
"EXT_CLK||INT"
$PN"3"16;
"VINM"
$PN"12"56;
"VINP"
$PN"13"45;
"VBUS"
$PN"11"14;
"SDA||SMBDAT"
$PN"4"51;
"SCL|||SMBCLK"
$PN"5"50;
"A0"
$PN"2"38;
"A1"
$PN"1"46;
"VCC"
$PN"9"33;
%"ISL28022FRZT"
"1","(-3550,3425)","0","pure_quanta","I29";
;
LOCATION"U56"
SEC"1"
PART_TYPE"SMLF"
VALUE"ISL28022FRZ-T"
MATERIAL"IC"
CDS_LIB"pure_quanta"
NEEDS_NO_SIZE"TRUE"
CDS_LMAN_SYM_OUTLINE"-300,300,300,-300"
SEC_TYPE""
PART_NUMBER"AL028022003";
"TH_GND"
$PN"TH"31;
"GND"
$PN"10"31;
"NC5"
$PN"16"17;
"NC4"
$PN"15"76;
"NC3"
$PN"14"34;
"NC2"
$PN"8"65;
"NC1"
$PN"7"35;
"NC0"
$PN"6"75;
"EXT_CLK||INT"
$PN"3"59;
"VINM"
$PN"12"55;
"VINP"
$PN"13"77;
"VBUS"
$PN"11"29;
"SDA||SMBDAT"
$PN"4"41;
"SCL|||SMBCLK"
$PN"5"42;
"A0"
$PN"2"43;
"A1"
$PN"1"44;
"VCC"
$PN"9"30;
%"UNIVERSAL_POWER"
"1","(-7225,5225)","0","pure_quanta_power","I3";
;
HDL_POWER"P12V_OCP_SFF"
CDS_LIB"pure_quanta_power";
"A"15;
%"Q_RES"
"1","(-1875,3675)","0","pure_quanta","I33";
;
LOCATION"R1271"
$SEC"1"
CDS_SEC"1"
VALUE"0"
MATERIAL"CHIP"
PACK_TYPE"0402LF"
CDS_LIB"pure_quanta"
TOLERANCE"5%"
WATTAGE"1/16W"
PART_NUMBER"CS00002JB13";
"B"
$PN"2"58;
"A"
$PN"1"59;
%"UNIVERSAL_GND"
"1","(-2975,2775)","0","pure_quanta_power","I34";
;
CDS_LIB"pure_quanta_power"
HDL_POWER"GND";
"A"31;
%"UNIVERSAL_POWER"
"1","(-4050,4425)","0","pure_quanta_power","I35";
;
HDL_POWER"P3V3_AUX"
CDS_LIB"pure_quanta_power";
"A"30;
%"Q_CAP"
"1","(-4300,4025)","0","pure_quanta","I36";
;
LOCATION"C1106"
$SEC"1"
CDS_SEC"1"
VALUE"0.1UF"
VOLTAGE"25V"
TOLERANCE"10%"
PACK_TYPE"0402"
MATERIAL"X7R"
CDS_LIB"pure_quanta"
PART_NUMBER"CH4104K1B00";
"B"
$PN"2"3;
"A"
$PN"1"30;
%"UNIVERSAL_GND"
"1","(-4300,3800)","0","pure_quanta_power","I37";
;
CDS_LIB"pure_quanta_power"
HDL_POWER"GND";
"A"3;
%"UNIVERSAL_POWER"
"1","(-4900,4325)","0","pure_quanta_power","I38";
;
HDL_POWER"P3V3_AUX"
CDS_LIB"pure_quanta_power";
"A"4;
%"Q_RES"
"2","(-4900,4025)","0","pure_quanta","I39";
;
LOCATION"R1322"
$SEC"1"
CDS_SEC"1"
MATERIAL"CHIP"
PACK_TYPE"0402LF"
WATTAGE"1/16W"
VALUE"4.7K"
TOLERANCE"1%"
CDS_LIB"pure_quanta"
PART_NUMBER"CS24702FB06";
"A"
$PN"1"4;
"B"
$PN"2"44;
%"UNIVERSAL_GND"
"1","(-7625,5375)","0","pure_quanta_power","I4";
;
CDS_LIB"pure_quanta_power"
HDL_POWER"GND";
"A"5;
%"Q_RES"
"1","(-5200,3375)","0","pure_quanta","I41";
;
LOCATION"R1277"
$SEC"1"
CDS_SEC"1"
VALUE"0"
TOLERANCE"5%"
MATERIAL"CHIP"
CDS_LIB"pure_quanta"
WATTAGE"1/16W"
PACK_TYPE"0402LF"
PART_NUMBER"CS00002JB13";
"B"
$PN"2"41;
"A"
$PN"1"52;
%"Q_RES"
"1","(-5200,3425)","0","pure_quanta","I42";
;
LOCATION"R1274"
$SEC"1"
CDS_SEC"1"
PACK_TYPE"0402LF"
MATERIAL"CHIP"
VALUE"0"
TOLERANCE"5%"
WATTAGE"1/16W"
CDS_LIB"pure_quanta"
PART_NUMBER"CS00002JB13";
"B"
$PN"2"42;
"A"
$PN"1"78;
%"Q_RES"
"1","(-5175,2825)","0","pure_quanta","I43";
;
LOCATION"R1291"
$SEC"1"
CDS_SEC"1"
TOLERANCE"1%"
WATTAGE"1/16W"
VALUE"10"
MATERIAL"CHIP"
PACK_TYPE"0402LF"
CDS_LIB"pure_quanta"
PART_NUMBER"CS01002FB07";
"B"
$PN"2"77;
"A"
$PN"1"27;
%"Q_RES"
"1","(-6000,3750)","0","pure_quanta","I44";
;
LOCATION"R1307"
$SEC"1"
CDS_SEC"1"
WATTAGE"1/16W"
MATERIAL"EMPTY"
VALUE"4.7K"
TOLERANCE"1%"
PACK_TYPE"0402LF"
CDS_LIB"pure_quanta"
PART_NUMBER"CS24702FB06";
"B"
$PN"2"44;
"A"
$PN"1"28;
%"Q_RES"
"1","(-6000,3675)","0","pure_quanta","I45";
;
LOCATION"R1310"
$SEC"1"
CDS_SEC"1"
PACK_TYPE"0402LF"
MATERIAL"EMPTY"
WATTAGE"1/16W"
TOLERANCE"1%"
VALUE"4.7K"
CDS_LIB"pure_quanta"
PART_NUMBER"CS24702FB06";
"B"
$PN"2"43;
"A"
$PN"1"28;
%"UNIVERSAL_POWER"
"1","(-6725,3925)","0","pure_quanta_power","I46";
;
HDL_POWER"P12V_OCP_V3_2"
CDS_LIB"pure_quanta_power";
"A"29;
%"UNIVERSAL_GND"
"1","(-6425,3500)","0","pure_quanta_power","I47";
;
CDS_LIB"pure_quanta_power"
HDL_POWER"GND";
"A"28;
%"Q_CAP"
"1","(-7625,5650)","0","pure_quanta","I5";
;
LOCATION"C1108"
$SEC"1"
CDS_SEC"1"
VALUE"0.1UF"
MATERIAL"X7R"
PACK_TYPE"0402"
TOLERANCE"10%"
VOLTAGE"25V"
CDS_LIB"pure_quanta"
PART_NUMBER"CH4104K1B00";
"B"
$PN"2"5;
"A"
$PN"1"14;
%"UNIVERSAL_POWER"
"1","(-6575,3175)","0","pure_quanta_power","I50";
;
HDL_POWER"P12V_OCP_V3_2"
CDS_LIB"pure_quanta_power";
"A"27;
%"Q_CAP"
"1","(-6975,3600)","0","pure_quanta","I51";
;
LOCATION"C1109"
$SEC"1"
CDS_SEC"1"
TOLERANCE"10%"
VOLTAGE"25V"
VALUE"0.1UF"
PACK_TYPE"0402"
MATERIAL"X7R"
CDS_LIB"pure_quanta"
PART_NUMBER"CH4104K1B00";
"B"
$PN"2"6;
"A"
$PN"1"29;
%"UNIVERSAL_GND"
"1","(-6975,3325)","0","pure_quanta_power","I52";
;
CDS_LIB"pure_quanta_power"
HDL_POWER"GND";
"A"6;
%"Q_RES"
"1","(-7075,3025)","0","pure_quanta","I53";
;
LOCATION"R1325"
$SEC"1"
CDS_SEC"1"
WATTAGE"2W"
VALUE"0.002"
TOLERANCE"1%"
MATERIAL"CHIP"
PACK_TYPE"2512LF"
CDS_LIB"pure_quanta"
PART_NUMBER"CS+002AFR06";
"B"
$PN"2"27;
"A"
$PN"1"26;
%"Q_CAP"
"1","(-4825,2675)","0","pure_quanta","I54";
;
LOCATION"C1112"
$SEC"1"
CDS_SEC"1"
VOLTAGE"25V"
PACK_TYPE"0402"
MATERIAL"X7R"
TOLERANCE"10%"
VALUE"0.1UF"
CDS_LIB"pure_quanta"
PART_NUMBER"CH4104K1B00";
"B"
$PN"2"55;
"A"
$PN"1"77;
%"Q_RES"
"1","(-5175,2550)","0","pure_quanta","I55";
;
LOCATION"R1302"
$SEC"1"
CDS_SEC"1"
VALUE"10"
MATERIAL"CHIP"
TOLERANCE"1%"
PACK_TYPE"0402LF"
WATTAGE"1/16W"
CDS_LIB"pure_quanta"
PART_NUMBER"CS01002FB07";
"B"
$PN"2"55;
"A"
$PN"1"26;
%"UNIVERSAL_POWER"
"1","(-7650,3175)","0","pure_quanta_power","I56";
;
HDL_POWER"P12V_OCP_V3_2_R"
CDS_LIB"pure_quanta_power";
"A"26;
%"ISL28022FRZT"
"1","(-4750,1150)","0","pure_quanta","I57";
;
LOCATION"U52"
SEC"1"
VALUE"ISL28022FRZ-T"
PART_TYPE"SMLF"
MATERIAL"IC"
SEC_TYPE""
CDS_LMAN_SYM_OUTLINE"-300,300,300,-300"
NEEDS_NO_SIZE"TRUE"
CDS_LIB"pure_quanta"
PART_NUMBER"AL028022003";
"TH_GND"
$PN"TH"24;
"GND"
$PN"10"24;
"NC5"
$PN"16"71;
"NC4"
$PN"15"63;
"NC3"
$PN"14"61;
"NC2"
$PN"8"62;
"NC1"
$PN"7"66;
"NC0"
$PN"6"64;
"EXT_CLK||INT"
$PN"3"57;
"VINM"
$PN"12"72;
"VINP"
$PN"13"73;
"VBUS"
$PN"11"20;
"SDA||SMBDAT"
$PN"4"49;
"SCL|||SMBCLK"
$PN"5"48;
"A0"
$PN"2"39;
"A1"
$PN"1"40;
"VCC"
$PN"9"25;
%"UNIVERSAL_GND"
"1","(-5500,1550)","0","pure_quanta_power","I58";
;
CDS_LIB"pure_quanta_power"
HDL_POWER"GND";
"A"7;
%"UNIVERSAL_POWER"
"1","(-5250,2150)","0","pure_quanta_power","I60";
;
HDL_POWER"P3V3_AUX"
CDS_LIB"pure_quanta_power";
"A"25;
%"Q_RES"
"1","(-3075,1400)","0","pure_quanta","I62";
;
LOCATION"R1269"
$SEC"1"
CDS_SEC"1"
VALUE"0"
MATERIAL"CHIP"
PACK_TYPE"0402LF"
WATTAGE"1/16W"
TOLERANCE"5%"
CDS_LIB"pure_quanta"
PART_NUMBER"CS00002JB13";
"B"
$PN"2"18;
"A"
$PN"1"57;
%"UNIVERSAL_GND"
"1","(-4175,500)","0","pure_quanta_power","I64";
;
CDS_LIB"pure_quanta_power"
HDL_POWER"GND";
"A"24;
%"UNIVERSAL_POWER"
"1","(-6100,2050)","0","pure_quanta_power","I65";
;
HDL_POWER"P3V3_AUX"
CDS_LIB"pure_quanta_power";
"A"8;
%"Q_CAP"
"1","(-5500,1750)","0","pure_quanta","I66";
;
LOCATION"C1096"
$SEC"1"
CDS_SEC"1"
PACK_TYPE"0402"
TOLERANCE"10%"
VALUE"0.1UF"
VOLTAGE"25V"
MATERIAL"X7R"
CDS_LIB"pure_quanta"
PART_NUMBER"CH4104K1B00";
"B"
$PN"2"7;
"A"
$PN"1"25;
%"Q_CAP"
"1","(-6025,400)","0","pure_quanta","I68";
;
LOCATION"C1110"
$SEC"1"
CDS_SEC"1"
MATERIAL"X7R"
TOLERANCE"10%"
VALUE"0.1UF"
VOLTAGE"25V"
PACK_TYPE"0402"
CDS_LIB"pure_quanta"
PART_NUMBER"CH4104K1B00";
"B"
$PN"2"72;
"A"
$PN"1"73;
%"Q_RES"
"1","(-6400,1100)","0","pure_quanta","I70";
;
LOCATION"R1275"
$SEC"1"
CDS_SEC"1"
TOLERANCE"5%"
VALUE"0"
MATERIAL"CHIP"
PACK_TYPE"0402LF"
WATTAGE"1/16W"
CDS_LIB"pure_quanta"
PART_NUMBER"CS00002JB13";
"B"
$PN"2"49;
"A"
$PN"1"47;
%"Q_RES"
"1","(-6400,1150)","0","pure_quanta","I71";
;
LOCATION"R1272"
$SEC"1"
CDS_SEC"1"
TOLERANCE"5%"
MATERIAL"CHIP"
VALUE"0"
WATTAGE"1/16W"
PACK_TYPE"0402LF"
CDS_LIB"pure_quanta"
PART_NUMBER"CS00002JB13";
"B"
$PN"2"48;
"A"
$PN"1"74;
%"Q_RES"
"1","(-7200,1475)","0","pure_quanta","I72";
;
LOCATION"R1305"
$SEC"1"
CDS_SEC"1"
TOLERANCE"1%"
MATERIAL"EMPTY"
PACK_TYPE"0402LF"
WATTAGE"1/16W"
VALUE"4.7K"
CDS_LIB"pure_quanta"
PART_NUMBER"CS24702FB06";
"B"
$PN"2"40;
"A"
$PN"1"23;
%"Q_RES"
"1","(-6375,550)","0","pure_quanta","I74";
;
LOCATION"R1283"
$SEC"1"
CDS_SEC"1"
MATERIAL"CHIP"
WATTAGE"1/16W"
VALUE"10"
PACK_TYPE"0402LF"
TOLERANCE"1%"
CDS_LIB"pure_quanta"
PART_NUMBER"CS01002FB07";
"B"
$PN"2"73;
"A"
$PN"1"22;
%"Q_RES"
"1","(-6375,275)","0","pure_quanta","I75";
;
LOCATION"R1292"
$SEC"1"
CDS_SEC"1"
PACK_TYPE"0402LF"
VALUE"10"
WATTAGE"1/16W"
MATERIAL"CHIP"
TOLERANCE"1%"
CDS_LIB"pure_quanta"
PART_NUMBER"CS01002FB07";
"B"
$PN"2"72;
"A"
$PN"1"19;
%"UNIVERSAL_GND"
"1","(-7625,1225)","0","pure_quanta_power","I76";
;
CDS_LIB"pure_quanta_power"
HDL_POWER"GND";
"A"23;
%"UNIVERSAL_POWER"
"1","(-7775,900)","0","pure_quanta_power","I79";
;
HDL_POWER"P12V_E1S_0"
CDS_LIB"pure_quanta_power";
"A"22;
%"UNIVERSAL_GND"
"1","(-7075,5550)","0","pure_quanta_power","I8";
;
CDS_LIB"pure_quanta_power"
HDL_POWER"GND";
"A"21;
%"UNIVERSAL_POWER"
"1","(-7925,1650)","0","pure_quanta_power","I80";
;
HDL_POWER"P12V_E1S_0"
CDS_LIB"pure_quanta_power";
"A"20;
%"Q_CAP"
"1","(-8175,1325)","0","pure_quanta","I81";
;
LOCATION"C1107"
$SEC"1"
CDS_SEC"1"
MATERIAL"X7R"
VOLTAGE"25V"
TOLERANCE"10%"
PACK_TYPE"0402"
VALUE"0.1UF"
CDS_LIB"pure_quanta"
PART_NUMBER"CH4104K1B00";
"B"
$PN"2"9;
"A"
$PN"1"20;
%"UNIVERSAL_GND"
"1","(-8175,1050)","0","pure_quanta_power","I82";
;
CDS_LIB"pure_quanta_power"
HDL_POWER"GND";
"A"9;
%"UNIVERSAL_POWER"
"1","(-8850,900)","0","pure_quanta_power","I83";
;
HDL_POWER"P12V_E1S_0_R"
CDS_LIB"pure_quanta_power";
"A"19;
%"Q_RES"
"1","(-8275,750)","0","pure_quanta","I84";
;
LOCATION"R1323"
$SEC"1"
CDS_SEC"1"
TOLERANCE"1%"
VALUE"0.002"
WATTAGE"2W"
PACK_TYPE"2512LF"
MATERIAL"CHIP"
CDS_LIB"pure_quanta"
PART_NUMBER"CS+002AFR06";
"B"
$PN"2"22;
"A"
$PN"1"19;
%"Q_RES"
"2","(-2025,6150)","0","pure_quanta","I85";
;
LOCATION"R1327"
$SEC"1"
CDS_SEC"1"
WATTAGE"1/16W"
MATERIAL"EMPTY"
PACK_TYPE"0402LF"
VALUE"1K"
TOLERANCE"1%"
CDS_LIB"pure_quanta"
PART_NUMBER"CS21002FB06";
"A"
$PN"1"10;
"B"
$PN"2"60;
%"UNIVERSAL_POWER"
"1","(-2025,6400)","0","pure_quanta_power","I86";
;
HDL_POWER"P3V3_AUX"
CDS_LIB"pure_quanta_power";
"A"10;
%"Q_RES"
"2","(-1400,4100)","0","pure_quanta","I87";
;
LOCATION"R1328"
$SEC"1"
CDS_SEC"1"
MATERIAL"EMPTY"
PACK_TYPE"0402LF"
WATTAGE"1/16W"
TOLERANCE"1%"
VALUE"1K"
CDS_LIB"pure_quanta"
PART_NUMBER"CS21002FB06";
"A"
$PN"1"11;
"B"
$PN"2"58;
%"UNIVERSAL_POWER"
"1","(-1400,4350)","0","pure_quanta_power","I88";
;
HDL_POWER"P3V3_AUX"
CDS_LIB"pure_quanta_power";
"A"11;
%"UNIVERSAL_POWER"
"1","(-2575,2050)","0","pure_quanta_power","I89";
;
HDL_POWER"P3V3_AUX"
CDS_LIB"pure_quanta_power";
"A"12;
%"UNIVERSAL_POWER"
"1","(-7375,5975)","0","pure_quanta_power","I9";
;
HDL_POWER"P12V_OCP_SFF"
CDS_LIB"pure_quanta_power";
"A"14;
%"Q_RES"
"2","(-2575,1800)","0","pure_quanta","I90";
;
LOCATION"R1326"
$SEC"1"
CDS_SEC"1"
VALUE"1K"
TOLERANCE"1%"
WATTAGE"1/16W"
MATERIAL"EMPTY"
PACK_TYPE"0402LF"
CDS_LIB"pure_quanta"
PART_NUMBER"CS21002FB06";
"A"
$PN"1"12;
"B"
$PN"2"18;
%"Q_RES"
"2","(-5475,5600)","0","pure_quanta","I92";
;
LOCATION"R1355"
$SEC"1"
CDS_SEC"1"
MATERIAL"CHIP"
VALUE"0"
TOLERANCE"5%"
WATTAGE"1/16W"
PACK_TYPE"0402LF"
CDS_LIB"pure_quanta"
PART_NUMBER"CS00002JB13";
"A"
$PN"1"38;
"B"
$PN"2"51;
%"Q_RES"
"2","(-4825,3550)","0","pure_quanta","I93";
;
LOCATION"R1360"
$SEC"1"
CDS_SEC"1"
PACK_TYPE"0402LF"
WATTAGE"1/16W"
MATERIAL"CHIP"
TOLERANCE"5%"
VALUE"0"
CDS_LIB"pure_quanta"
PART_NUMBER"CS00002JB13";
"A"
$PN"1"43;
"B"
$PN"2"42;
%"Q_RES"
"2","(-6025,1300)","0","pure_quanta","I94";
;
LOCATION"R1350"
$SEC"1"
CDS_SEC"1"
WATTAGE"1/16W"
PACK_TYPE"0402LF"
MATERIAL"CHIP"
TOLERANCE"5%"
VALUE"0"
CDS_LIB"pure_quanta"
PART_NUMBER"CS00002JB13";
"A"
$PN"1"40;
"B"
$PN"2"49;
%"Q_RES"
"2","(-6100,1750)","0","pure_quanta","I95";
;
LOCATION"R1317"
$SEC"1"
CDS_SEC"1"
TOLERANCE"1%"
MATERIAL"EMPTY"
WATTAGE"1/16W"
VALUE"4.7K"
PACK_TYPE"0402LF"
CDS_LIB"pure_quanta"
PART_NUMBER"CS24702FB06";
"A"
$PN"1"8;
"B"
$PN"2"40;
%"Q_RES"
"1","(-7200,1425)","0","pure_quanta","I96";
;
LOCATION"R1308"
$SEC"1"
CDS_SEC"1"
PACK_TYPE"0402LF"
VALUE"4.7K"
MATERIAL"CHIP"
CDS_LIB"pure_quanta"
WATTAGE"1/16W"
TOLERANCE"1%"
PART_NUMBER"CS24702FB06";
"B"
$PN"2"39;
"A"
$PN"1"23;
END.
